# S9S_MB_2U (Grand Teton) — schematic netlist excerpt (pin names and nets, part order shuffled) for the footprints in the layout excerpt that follows; sources: Cadence DE-HDL packaged netlist, KiCad conversion of 03242023_DA0F0TMBIJ0_F0T_Motherboard_J_brd_V01_OCP.brd

C2052  Q_CAP  0.1UF 25V 10% X7R  pkg 0402  page 250 : A = P3V3_ADC128_VCC ; B = GND
R1269  Q_RES  4.75K 1% CHIP  pkg 0402LF  page 183 : A = IRQ_BMC_PCH_NMI ; B = GND

(kicad_pcb
	(version 20260206)
	(generator "pcbnew")
	(generator_version "10.0")
	(general
		(thickness 1.6)
		(legacy_teardrops no)
	)
	(paper "A4")
	(title_block
		(title "03242023_DA0F0TMBIJ0_F0T_Motherboard_J_brd_V01_OCP.brd")
		(comment 1 "Grand Teton / footprints 1711-1712 of 6105")
	)
	(layers
		(0 "F.Cu" signal "TOP")
		(4 "In1.Cu" signal "GND")
		(6 "In2.Cu" signal "IN1")
		(8 "In3.Cu" signal "GND1")
		(10 "In4.Cu" signal "IN2")
		(12 "In5.Cu" signal "GND2")
		(14 "In6.Cu" signal "IN3")
		(16 "In7.Cu" signal "GND3")
		(18 "In8.Cu" signal "VCC")
		(20 "In9.Cu" signal "VCC1")
		(22 "In10.Cu" signal "GND4")
		(24 "In11.Cu" signal "IN4")
		(26 "In12.Cu" signal "GND5")
		(28 "In13.Cu" signal "IN5")
		(30 "In14.Cu" signal "GND6")
		(32 "In15.Cu" signal "IN6")
		(34 "In16.Cu" signal "GND7")
		(2 "B.Cu" signal "BOTTOM")
		(9 "F.Adhes" user "F.Adhesive")
		(11 "B.Adhes" user "B.Adhesive")
		(13 "F.Paste" user "Package Geometry/Pastemask Top")
		(15 "B.Paste" user "Package Geometry/Pastemask Bottom")
		(5 "F.SilkS" user "Ref Des/Silkscreen Top")
		(7 "B.SilkS" user "Ref Des/Silkscreen Bottom")
		(1 "F.Mask" user "Board Geometry/Soldermask Top")
		(3 "B.Mask" user "Board Geometry/Soldermask Bottom")
		(17 "Dwgs.User" user "User.Drawings")
		(19 "Cmts.User" user "User.Comments")
		(21 "Eco1.User" user "User.Eco1")
		(23 "Eco2.User" user "User.Eco2")
		(25 "Edge.Cuts" user "Board Geometry/Outline")
		(27 "Margin" user)
		(31 "F.CrtYd" user "Package Geometry/Place Bound Top")
		(29 "B.CrtYd" user "Package Geometry/Place Bound Bottom")
		(35 "F.Fab" user "Ref Des/Assembly Top")
		(33 "B.Fab" user "Ref Des/Assembly Bottom")
	)
	(footprint ""
		(layer "F.Cu")
		(at 329.948794 -21.625052 180)
		(property "Reference" "R1269"
			(at 0 0 180)
			(layer "F.SilkS")
			(hide yes)
			(effects
				(font
					(size 1.27 1.27)
				)
			)
		)
		(property "Value" ""
			(at 0 0 180)
			(layer "F.Fab")
			(effects
				(font
					(size 1.27 1.27)
				)
			)
		)
		(duplicate_pad_numbers_are_jumpers no)
		(fp_line
			(start 0.7874 0.4064)
			(end -0.7874 0.4064)
			(stroke
				(width 0.1524)
				(type default)
			)
			(layer "F.SilkS")
		)
		(fp_line
			(start 0.7874 -0.4064)
			(end 0.7874 0.4064)
			(stroke
				(width 0.1524)
				(type default)
			)
			(layer "F.SilkS")
		)
		(fp_line
			(start -0.7874 0.4064)
			(end -0.7874 -0.4064)
			(stroke
				(width 0.1524)
				(type default)
			)
			(layer "F.SilkS")
		)
		(fp_line
			(start -0.7874 -0.4064)
			(end 0.7874 -0.4064)
			(stroke
				(width 0.1524)
				(type default)
			)
			(layer "F.SilkS")
		)
		(fp_line
			(start 0.67945 0.3048)
			(end 0.120396 0.3048)
			(stroke
				(width 0.1)
				(type default)
			)
			(layer "F.Fab")
		)
		(fp_line
			(start 0.67945 -0.3048)
			(end 0.67945 0.3048)
			(stroke
				(width 0.1)
				(type default)
			)
			(layer "F.Fab")
		)
		(fp_line
			(start 0.12065 -0.2794)
			(end 0.12065 -0.3048)
			(stroke
				(width 0.1)
				(type default)
			)
			(layer "F.Fab")
		)
		(fp_line
			(start 0.12065 -0.3048)
			(end 0.67945 -0.3048)
			(stroke
				(width 0.1)
				(type default)
			)
			(layer "F.Fab")
		)
		(fp_line
			(start 0.120396 0.3048)
			(end 0.120396 0.2794)
			(stroke
				(width 0.1)
				(type default)
			)
			(layer "F.Fab")
		)
		(fp_line
			(start 0.120396 0.2794)
			(end -0.12065 0.2794)
			(stroke
				(width 0.1)
				(type default)
			)
			(layer "F.Fab")
		)
		(fp_line
			(start -0.12065 0.3048)
			(end -0.67945 0.3048)
			(stroke
				(width 0.1)
				(type default)
			)
			(layer "F.Fab")
		)
		(fp_line
			(start -0.12065 0.2794)
			(end -0.12065 0.3048)
			(stroke
				(width 0.1)
				(type default)
			)
			(layer "F.Fab")
		)
		(fp_line
			(start -0.12065 -0.2794)
			(end 0.12065 -0.2794)
			(stroke
				(width 0.1)
				(type default)
			)
			(layer "F.Fab")
		)
		(fp_line
			(start -0.12065 -0.305054)
			(end -0.12065 -0.2794)
			(stroke
				(width 0.1)
				(type default)
			)
			(layer "F.Fab")
		)
		(fp_line
			(start -0.67945 0.3048)
			(end -0.67945 -0.305054)
			(stroke
				(width 0.1)
				(type default)
			)
			(layer "F.Fab")
		)
		(fp_line
			(start -0.67945 -0.305054)
			(end -0.12065 -0.305054)
			(stroke
				(width 0.1)
				(type default)
			)
			(layer "F.Fab")
		)
		(pad "1" smd circle
			(at -0.40005 0 180)
			(size 0 0)
			(layers "F.Cu" "F.Mask" "F.Paste")
			(net "IRQ_BMC_PCH_NMI")
		)
		(pad "2" smd circle
			(at 0.40005 0 180)
			(size 0 0)
			(layers "F.Cu" "F.Mask" "F.Paste")
			(net "GND")
		)
	)
	(footprint ""
		(layer "F.Cu")
		(at 20.190714 -109.859826 180)
		(property "Reference" "C2052"
			(at 0 0 180)
			(layer "F.SilkS")
			(hide yes)
			(effects
				(font
					(size 1.27 1.27)
				)
			)
		)
		(property "Value" ""
			(at 0 0 180)
			(layer "F.Fab")
			(effects
				(font
					(size 1.27 1.27)
				)
			)
		)
		(duplicate_pad_numbers_are_jumpers no)
		(fp_line
			(start 0.7874 0.4064)
			(end -0.7874 0.4064)
			(stroke
				(width 0.1524)
				(type default)
			)
			(layer "F.SilkS")
		)
		(fp_line
			(start 0.7874 -0.4064)
			(end 0.7874 0.4064)
			(stroke
				(width 0.1524)
				(type default)
			)
			(layer "F.SilkS")
		)
		(fp_line
			(start -0.7874 0.4064)
			(end -0.7874 -0.4064)
			(stroke
				(width 0.1524)
				(type default)
			)
			(layer "F.SilkS")
		)
		(fp_line
			(start -0.7874 -0.4064)
			(end 0.7874 -0.4064)
			(stroke
				(width 0.1524)
				(type default)
			)
			(layer "F.SilkS")
		)
		(fp_line
			(start 0.67945 0.3048)
			(end 0.120396 0.3048)
			(stroke
				(width 0.1)
				(type default)
			)
			(layer "F.Fab")
		)
		(fp_line
			(start 0.67945 -0.3048)
			(end 0.67945 0.3048)
			(stroke
				(width 0.1)
				(type default)
			)
			(layer "F.Fab")
		)
		(fp_line
			(start 0.12065 -0.2794)
			(end 0.12065 -0.3048)
			(stroke
				(width 0.1)
				(type default)
			)
			(layer "F.Fab")
		)
		(fp_line
			(start 0.12065 -0.3048)
			(end 0.67945 -0.3048)
			(stroke
				(width 0.1)
				(type default)
			)
			(layer "F.Fab")
		)
		(fp_line
			(start 0.120396 0.3048)
			(end 0.120396 0.2794)
			(stroke
				(width 0.1)
				(type default)
			)
			(layer "F.Fab")
		)
		(fp_line
			(start 0.120396 0.2794)
			(end -0.12065 0.2794)
			(stroke
				(width 0.1)
				(type default)
			)
			(layer "F.Fab")
		)
		(fp_line
			(start -0.12065 0.3048)
			(end -0.67945 0.3048)
			(stroke
				(width 0.1)
				(type default)
			)
			(layer "F.Fab")
		)
		(fp_line
			(start -0.12065 0.2794)
			(end -0.12065 0.3048)
			(stroke
				(width 0.1)
				(type default)
			)
			(layer "F.Fab")
		)
		(fp_line
			(start -0.12065 -0.2794)
			(end 0.12065 -0.2794)
			(stroke
				(width 0.1)
				(type default)
			)
			(layer "F.Fab")
		)
		(fp_line
			(start -0.12065 -0.305054)
			(end -0.12065 -0.2794)
			(stroke
				(width 0.1)
				(type default)
			)
			(layer "F.Fab")
		)
		(fp_line
			(start -0.67945 0.3048)
			(end -0.67945 -0.305054)
			(stroke
				(width 0.1)
				(type default)
			)
			(layer "F.Fab")
		)
		(fp_line
			(start -0.67945 -0.305054)
			(end -0.12065 -0.305054)
			(stroke
				(width 0.1)
				(type default)
			)
			(layer "F.Fab")
		)
		(pad "1" smd circle
			(at -0.40005 0 180)
			(size 0 0)
			(layers "F.Cu" "F.Mask" "F.Paste")
			(net "P3V3_ADC128_VCC")
		)
		(pad "2" smd circle
			(at 0.40005 0 180)
			(size 0 0)
			(layers "F.Cu" "F.Mask" "F.Paste")
			(net "GND")
		)
	)
)
